(kicad_pcb
	(version 20260206)
	(generator "pcbnew")
	(generator_version "10.0")
	(general
		(thickness 1.6)
		(legacy_teardrops no)
	)
	(paper "A4")
	(title_block
		(title "v1-chassis-manager — T6M_CM_d_v01_1031_1645.brd")
		(comment 1 "Open CloudServer (Microsoft) / footprints 1447-1452 of 2512")
	)
	(layers
		(0 "F.Cu" signal "TOP")
		(4 "In1.Cu" signal "GND1")
		(6 "In2.Cu" signal "IN1")
		(8 "In3.Cu" signal "VCC1")
		(10 "In4.Cu" signal "VCC2")
		(12 "In5.Cu" signal "GND2")
		(14 "In6.Cu" signal "IN2")
		(16 "In7.Cu" signal "IN3")
		(18 "In8.Cu" signal "GND3")
		(2 "B.Cu" signal "BOTTOM")
		(9 "F.Adhes" user "F.Adhesive")
		(11 "B.Adhes" user "B.Adhesive")
		(13 "F.Paste" user "Package Geometry/Pastemask Top")
		(15 "B.Paste" user "Package Geometry/Pastemask Bottom")
		(5 "F.SilkS" user "Ref Des/Silkscreen Top")
		(7 "B.SilkS" user "Ref Des/Silkscreen Bottom")
		(1 "F.Mask" user "Board Geometry/Soldermask Top")
		(3 "B.Mask" user "Board Geometry/Soldermask Bottom")
		(17 "Dwgs.User" user "User.Drawings")
		(19 "Cmts.User" user "User.Comments")
		(21 "Eco1.User" user "User.Eco1")
		(23 "Eco2.User" user "User.Eco2")
		(25 "Edge.Cuts" user "Board Geometry/Outline")
		(27 "Margin" user)
		(31 "F.CrtYd" user "Package Geometry/Place Bound Top")
		(29 "B.CrtYd" user "Package Geometry/Place Bound Bottom")
		(35 "F.Fab" user "Ref Des/Assembly Top")
		(33 "B.Fab" user "Ref Des/Assembly Bottom")
	)
	(footprint ""
		(layer "F.Cu")
		(at 48.24476 -182.246524 90)
		(property "Reference" "C611"
			(at -133.313932 -3.637788 90)
			(unlocked yes)
			(layer "F.SilkS")
			(effects
				(font
					(size 0.7874 0.5842)
					(thickness 0.1524)
				)
				(justify left)
			)
		)
		(property "Value" ""
			(at 0 0 90)
			(layer "F.Fab")
			(effects
				(font
					(size 1.27 1.27)
				)
			)
		)
		(duplicate_pad_numbers_are_jumpers no)
		(fp_line
			(start 0.7874 -0.4064)
			(end 0.7874 0.4064)
			(stroke
				(width 0.1524)
				(type default)
			)
			(layer "F.SilkS")
		)
		(fp_line
			(start -0.7874 -0.4064)
			(end 0.7874 -0.4064)
			(stroke
				(width 0.1524)
				(type default)
			)
			(layer "F.SilkS")
		)
		(fp_line
			(start 0 0.381)
			(end 0 -0.381)
			(stroke
				(width 0.1524)
				(type default)
			)
			(layer "F.SilkS")
		)
		(fp_line
			(start 0.7874 0.4064)
			(end -0.7874 0.4064)
			(stroke
				(width 0.1524)
				(type default)
			)
			(layer "F.SilkS")
		)
		(fp_line
			(start -0.7874 0.4064)
			(end -0.7874 -0.4064)
			(stroke
				(width 0.1524)
				(type default)
			)
			(layer "F.SilkS")
		)
		(fp_poly
			(pts
				(xy -0.5334 0.254) (xy -0.635 0.254) (xy -0.635 0.2286) (xy -0.635 -0.254) (xy -0.5334 -0.254) (xy -0.5334 -0.2794)
				(xy 0.5334 -0.2794) (xy 0.5334 -0.254) (xy 0.635 -0.254) (xy 0.635 0.254) (xy 0.5334 0.254) (xy 0.5334 0.2794)
				(xy -0.508 0.2794) (xy -0.5334 0.2794)
			)
			(stroke
				(width 0)
				(type default)
			)
			(fill no)
			(layer "F.CrtYd")
		)
		(pad "1" smd rect
			(at 0.40005 0 90)
			(size 0.4572 0.508)
			(layers "F.Cu" "F.Mask" "F.Paste")
			(net "PSU5_AC_OK")
		)
		(pad "2" smd rect
			(at -0.40005 0 90)
			(size 0.4572 0.508)
			(layers "F.Cu" "F.Mask" "F.Paste")
			(net "GND")
		)
	)
	(footprint ""
		(layer "F.Cu")
		(at 102.006654 -133.119114 180)
		(property "Reference" "PR44"
			(at 4.38404 8.411972 0)
			(unlocked yes)
			(layer "F.SilkS")
			(effects
				(font
					(size 0.7874 0.5842)
					(thickness 0.1524)
				)
				(justify left)
			)
		)
		(property "Value" ""
			(at 0 0 180)
			(layer "F.Fab")
			(effects
				(font
					(size 1.27 1.27)
				)
			)
		)
		(duplicate_pad_numbers_are_jumpers no)
		(fp_line
			(start 0.7874 0.4064)
			(end -0.7874 0.4064)
			(stroke
				(width 0.1524)
				(type default)
			)
			(layer "F.SilkS")
		)
		(fp_line
			(start 0.7874 -0.4064)
			(end 0.7874 0.4064)
			(stroke
				(width 0.1524)
				(type default)
			)
			(layer "F.SilkS")
		)
		(fp_line
			(start -0.7874 0.4064)
			(end -0.7874 -0.4064)
			(stroke
				(width 0.1524)
				(type default)
			)
			(layer "F.SilkS")
		)
		(fp_line
			(start -0.7874 -0.4064)
			(end 0.7874 -0.4064)
			(stroke
				(width 0.1524)
				(type default)
			)
			(layer "F.SilkS")
		)
		(fp_poly
			(pts
				(xy -0.508 0.2794) (xy -0.508 0.2286) (xy -0.635 0.2286) (xy -0.635 -0.254) (xy -0.5334 -0.254)
				(xy -0.5334 -0.2794) (xy 0.5334 -0.2794) (xy 0.5334 -0.254) (xy 0.635 -0.254) (xy 0.635 0.254) (xy 0.5334 0.254)
				(xy 0.5334 0.2794)
			)
			(stroke
				(width 0)
				(type default)
			)
			(fill no)
			(layer "F.CrtYd")
		)
		(pad "1" smd rect
			(at 0.40005 0 180)
			(size 0.4572 0.508)
			(layers "F.Cu" "F.Mask" "F.Paste")
			(net "SVID_CPU_NODE1_PVCCP_CLK")
		)
		(pad "2" smd rect
			(at -0.40005 0 180)
			(size 0.4572 0.508)
			(layers "F.Cu" "F.Mask" "F.Paste")
			(net "SVID_CPU_NODE1_CLK_R")
		)
	)
	(footprint ""
		(layer "F.Cu")
		(at 164.12337 -136.064498 180)
		(property "Reference" "S1"
			(at -0.46101 3.601466 0)
			(unlocked yes)
			(layer "F.SilkS")
			(effects
				(font
					(size 0.7874 0.5842)
					(thickness 0.1524)
				)
				(justify left)
			)
		)
		(property "Value" ""
			(at 0 0 180)
			(layer "F.Fab")
			(effects
				(font
					(size 1.27 1.27)
				)
			)
		)
		(duplicate_pad_numbers_are_jumpers no)
		(fp_line
			(start 3.0988 3.0988)
			(end 3.0988 2.667)
			(stroke
				(width 0.1524)
				(type default)
			)
			(layer "F.SilkS")
		)
		(fp_line
			(start 3.0988 1.3208)
			(end 3.0988 -1.3208)
			(stroke
				(width 0.1524)
				(type default)
			)
			(layer "F.SilkS")
		)
		(fp_line
			(start 3.0988 -3.0988)
			(end 3.0988 -2.667)
			(stroke
				(width 0.1524)
				(type default)
			)
			(layer "F.SilkS")
		)
		(fp_line
			(start -3.0988 3.0988)
			(end 3.0988 3.0988)
			(stroke
				(width 0.1524)
				(type default)
			)
			(layer "F.SilkS")
		)
		(fp_line
			(start -3.0988 2.6416)
			(end -3.0988 3.0988)
			(stroke
				(width 0.1524)
				(type default)
			)
			(layer "F.SilkS")
		)
		(fp_line
			(start -3.0988 -1.3462)
			(end -3.0988 1.3208)
			(stroke
				(width 0.1524)
				(type default)
			)
			(layer "F.SilkS")
		)
		(fp_line
			(start -3.0988 -2.667)
			(end -3.0988 -3.0988)
			(stroke
				(width 0.1524)
				(type default)
			)
			(layer "F.SilkS")
		)
		(fp_line
			(start -3.0988 -3.0988)
			(end 3.0988 -3.0988)
			(stroke
				(width 0.1524)
				(type default)
			)
			(layer "F.SilkS")
		)
		(fp_poly
			(pts
				(xy -3.987038 -2.765044) (xy -6.019038 -2.180844) (xy -6.019038 -3.476244)
			)
			(stroke
				(width 0)
				(type default)
			)
			(fill yes)
			(layer "F.SilkS")
		)
		(fp_poly
			(pts
				(xy -3.0988 3.0988) (xy -3.0988 2.5146) (xy -5.0038 2.5146) (xy -5.0038 1.4732) (xy -3.0988 1.4732)
				(xy -3.0988 -1.4986) (xy -5.0038 -1.4986) (xy -5.0038 -2.5146) (xy -3.0988 -2.5146) (xy -3.0988 -3.0988)
				(xy 3.0988 -3.0988) (xy 3.0988 -2.5146) (xy 5.0038 -2.5146) (xy 5.0038 -1.4732) (xy 3.0988 -1.4732)
				(xy 3.0988 1.4732) (xy 5.0038 1.4732) (xy 5.0038 2.5146) (xy 3.0988 2.5146) (xy 3.0988 3.0988)
			)
			(stroke
				(width 0)
				(type default)
			)
			(fill no)
			(layer "F.CrtYd")
		)
		(fp_text user "2"
			(at 5.571236 -2.078228 0)
			(unlocked yes)
			(layer "F.SilkS")
			(effects
				(font
					(size 0.635 0.4064)
					(thickness 0.1524)
				)
				(justify left)
			)
		)
		(fp_text user "4"
			(at 5.023866 0.972566 0)
			(unlocked yes)
			(layer "F.SilkS")
			(effects
				(font
					(size 0.635 0.4064)
					(thickness 0.1524)
				)
				(justify left)
			)
		)
		(fp_text user "3"
			(at -5.189474 2.14122 0)
			(unlocked yes)
			(layer "F.SilkS")
			(effects
				(font
					(size 0.635 0.4064)
					(thickness 0.1524)
				)
				(justify left)
			)
		)
		(fp_text user "1"
			(at -5.226304 -1.949196 0)
			(unlocked yes)
			(layer "F.SilkS")
			(effects
				(font
					(size 0.635 0.4064)
					(thickness 0.1524)
				)
				(justify left)
			)
		)
		(pad "1" smd rect
			(at -3.400044 -1.999996 270)
			(size 1.016 3.2004)
			(layers "F.Cu" "F.Mask" "F.Paste")
			(net "PWR_BTN_NODE1_L")
		)
		(pad "2" smd rect
			(at 3.400044 -1.999996 270)
			(size 1.016 3.2004)
			(layers "F.Cu" "F.Mask" "F.Paste")
			(net "PWR_BTN_NODE1_L")
		)
		(pad "3" smd rect
			(at -3.400044 1.999996 270)
			(size 1.016 3.2004)
			(layers "F.Cu" "F.Mask" "F.Paste")
			(net "GND")
		)
		(pad "4" smd rect
			(at 3.400044 1.999996 270)
			(size 1.016 3.2004)
			(layers "F.Cu" "F.Mask" "F.Paste")
			(net "GND")
		)
	)
	(footprint ""
		(layer "F.Cu")
		(at 102.060248 -137.192258)
		(property "Reference" "PR54"
			(at -4.437634 -8.420608 0)
			(unlocked yes)
			(layer "F.SilkS")
			(effects
				(font
					(size 0.7874 0.5842)
					(thickness 0.1524)
				)
				(justify left)
			)
		)
		(property "Value" ""
			(at 0 0 0)
			(layer "F.Fab")
			(effects
				(font
					(size 1.27 1.27)
				)
			)
		)
		(duplicate_pad_numbers_are_jumpers no)
		(fp_line
			(start -0.7874 -0.4064)
			(end 0.7874 -0.4064)
			(stroke
				(width 0.1524)
				(type default)
			)
			(layer "F.SilkS")
		)
		(fp_line
			(start -0.7874 0.4064)
			(end -0.7874 -0.4064)
			(stroke
				(width 0.1524)
				(type default)
			)
			(layer "F.SilkS")
		)
		(fp_line
			(start 0.7874 -0.4064)
			(end 0.7874 0.4064)
			(stroke
				(width 0.1524)
				(type default)
			)
			(layer "F.SilkS")
		)
		(fp_line
			(start 0.7874 0.4064)
			(end -0.7874 0.4064)
			(stroke
				(width 0.1524)
				(type default)
			)
			(layer "F.SilkS")
		)
		(fp_poly
			(pts
				(xy -0.508 0.2794) (xy -0.508 0.2286) (xy -0.635 0.2286) (xy -0.635 -0.254) (xy -0.5334 -0.254)
				(xy -0.5334 -0.2794) (xy 0.5334 -0.2794) (xy 0.5334 -0.254) (xy 0.635 -0.254) (xy 0.635 0.254) (xy 0.5334 0.254)
				(xy 0.5334 0.2794)
			)
			(stroke
				(width 0)
				(type default)
			)
			(fill no)
			(layer "F.CrtYd")
		)
		(pad "1" smd rect
			(at 0.40005 0)
			(size 0.4572 0.508)
			(layers "F.Cu" "F.Mask" "F.Paste")
			(net "H_CPU_NODE1_VR_HOT_L")
		)
		(pad "2" smd rect
			(at -0.40005 0)
			(size 0.4572 0.508)
			(layers "F.Cu" "F.Mask" "F.Paste")
			(net "P3V3_NODE1")
		)
	)
	(footprint ""
		(layer "F.Cu")
		(at 56.721756 -14.910054 -90)
		(property "Reference" "PC83"
			(at 0.031242 5.737606 90)
			(unlocked yes)
			(layer "F.SilkS")
			(effects
				(font
					(size 0.7874 0.5842)
					(thickness 0.1524)
				)
				(justify left)
			)
		)
		(property "Value" ""
			(at 0 0 270)
			(layer "F.Fab")
			(effects
				(font
					(size 1.27 1.27)
				)
			)
		)
		(duplicate_pad_numbers_are_jumpers no)
		(fp_line
			(start -1.905 0.8636)
			(end -1.905 -0.8636)
			(stroke
				(width 0.1524)
				(type default)
			)
			(layer "F.SilkS")
		)
		(fp_line
			(start 1.905 0.8636)
			(end -1.905 0.8636)
			(stroke
				(width 0.1524)
				(type default)
			)
			(layer "F.SilkS")
		)
		(fp_line
			(start 0 0.8382)
			(end 0 -0.8382)
			(stroke
				(width 0.1524)
				(type default)
			)
			(layer "F.SilkS")
		)
		(fp_line
			(start -1.905 -0.8636)
			(end 1.905 -0.8636)
			(stroke
				(width 0.1524)
				(type default)
			)
			(layer "F.SilkS")
		)
		(fp_line
			(start 1.905 -0.8636)
			(end 1.905 0.8636)
			(stroke
				(width 0.1524)
				(type default)
			)
			(layer "F.SilkS")
		)
		(fp_rect
			(start -1.524 0.7366)
			(end 1.524 -0.7366)
			(stroke
				(width 0)
				(type default)
			)
			(fill no)
			(layer "F.CrtYd")
		)
		(pad "1" smd rect
			(at 0.94996 0 270)
			(size 1.1176 1.3716)
			(layers "F.Cu" "F.Mask" "F.Paste")
			(net "PV_VDDR_NODE1")
		)
		(pad "2" smd rect
			(at -0.94996 0 270)
			(size 1.1176 1.3716)
			(layers "F.Cu" "F.Mask" "F.Paste")
			(net "GND")
		)
	)
	(footprint ""
		(layer "F.Cu")
		(at 49.38776 -188.126624 90)
		(property "Reference" "R850"
			(at 4.548886 0.205232 90)
			(unlocked yes)
			(layer "F.SilkS")
			(effects
				(font
					(size 0.7874 0.5842)
					(thickness 0.1524)
				)
				(justify left)
			)
		)
		(property "Value" ""
			(at 0 0 90)
			(layer "F.Fab")
			(effects
				(font
					(size 1.27 1.27)
				)
			)
		)
		(duplicate_pad_numbers_are_jumpers no)
		(fp_line
			(start 0.7874 -0.4064)
			(end 0.7874 0.4064)
			(stroke
				(width 0.1524)
				(type default)
			)
			(layer "F.SilkS")
		)
		(fp_line
			(start -0.7874 -0.4064)
			(end 0.7874 -0.4064)
			(stroke
				(width 0.1524)
				(type default)
			)
			(layer "F.SilkS")
		)
		(fp_line
			(start 0.7874 0.4064)
			(end -0.7874 0.4064)
			(stroke
				(width 0.1524)
				(type default)
			)
			(layer "F.SilkS")
		)
		(fp_line
			(start -0.7874 0.4064)
			(end -0.7874 -0.4064)
			(stroke
				(width 0.1524)
				(type default)
			)
			(layer "F.SilkS")
		)
		(fp_poly
			(pts
				(xy -0.508 0.2794) (xy -0.508 0.2286) (xy -0.635 0.2286) (xy -0.635 -0.254) (xy -0.5334 -0.254)
				(xy -0.5334 -0.2794) (xy 0.5334 -0.2794) (xy 0.5334 -0.254) (xy 0.635 -0.254) (xy 0.635 0.254) (xy 0.5334 0.254)
				(xy 0.5334 0.2794)
			)
			(stroke
				(width 0)
				(type default)
			)
			(fill no)
			(layer "F.CrtYd")
		)
		(pad "1" smd rect
			(at 0.40005 0 90)
			(size 0.4572 0.508)
			(layers "F.Cu" "F.Mask" "F.Paste")
			(net "PSU4_AC_OK_R")
		)
		(pad "2" smd rect
			(at -0.40005 0 90)
			(size 0.4572 0.508)
			(layers "F.Cu" "F.Mask" "F.Paste")
			(net "GND")
		)
	)
)
